(kicad_pcb
	(version 20260206)
	(generator "pcbnew")
	(generator_version "10.0")
	(general
		(thickness 1.6)
		(legacy_teardrops no)
	)
	(paper "A4")
	(title_block
		(title "03242023_DA0F0TMBIJ0_F0T_Motherboard_J_brd_V01_OCP.brd")
		(comment 1 "Grand Teton / footprint 3039 of 6105 (U2), pads 2806-2916 of 4677")
	)
	(layers
		(0 "F.Cu" signal "TOP")
		(4 "In1.Cu" signal "GND")
		(6 "In2.Cu" signal "IN1")
		(8 "In3.Cu" signal "GND1")
		(10 "In4.Cu" signal "IN2")
		(12 "In5.Cu" signal "GND2")
		(14 "In6.Cu" signal "IN3")
		(16 "In7.Cu" signal "GND3")
		(18 "In8.Cu" signal "VCC")
		(20 "In9.Cu" signal "VCC1")
		(22 "In10.Cu" signal "GND4")
		(24 "In11.Cu" signal "IN4")
		(26 "In12.Cu" signal "GND5")
		(28 "In13.Cu" signal "IN5")
		(30 "In14.Cu" signal "GND6")
		(32 "In15.Cu" signal "IN6")
		(34 "In16.Cu" signal "GND7")
		(2 "B.Cu" signal "BOTTOM")
		(9 "F.Adhes" user "F.Adhesive")
		(11 "B.Adhes" user "B.Adhesive")
		(13 "F.Paste" user "Package Geometry/Pastemask Top")
		(15 "B.Paste" user "Package Geometry/Pastemask Bottom")
		(5 "F.SilkS" user "Ref Des/Silkscreen Top")
		(7 "B.SilkS" user "Ref Des/Silkscreen Bottom")
		(1 "F.Mask" user "Board Geometry/Soldermask Top")
		(3 "B.Mask" user "Board Geometry/Soldermask Bottom")
		(17 "Dwgs.User" user "User.Drawings")
		(19 "Cmts.User" user "User.Comments")
		(21 "Eco1.User" user "User.Eco1")
		(23 "Eco2.User" user "User.Eco2")
		(25 "Edge.Cuts" user "Board Geometry/Outline")
		(27 "Margin" user)
		(31 "F.CrtYd" user "Package Geometry/Place Bound Top")
		(29 "B.CrtYd" user "Package Geometry/Place Bound Bottom")
		(35 "F.Fab" user "Ref Des/Assembly Top")
		(33 "B.Fab" user "Ref Des/Assembly Bottom")
	)
	(footprint ""
		(layer "F.Cu")
		(at 359.870248 -251.76988 90)
		(property "Reference" "U2"
			(at -74.416158 -44.488608 0)
			(unlocked yes)
			(layer "F.SilkS")
			(effects
				(font
					(size 1.6002 1.1938)
					(thickness 0.1524)
				)
				(justify left)
			)
		)
		(property "Value" ""
			(at 0 0 90)
			(layer "F.Fab")
			(effects
				(font
					(size 1.27 1.27)
				)
			)
		)
		(duplicate_pad_numbers_are_jumpers no)
		(pad "DK22" smd circle
			(at -20.333462 14.746732 270)
			(size 0.4318 0.4318)
			(layers "F.Cu" "F.Mask" "F.Paste")
			(net "M_H_CPU0_SB_DQ<17>")
		)
		(pad "DK24" smd circle
			(at -18.705576 14.746732 270)
			(size 0.4318 0.4318)
			(layers "F.Cu" "F.Mask" "F.Paste")
			(net "GND")
		)
		(pad "DK26" smd circle
			(at -17.07769 14.746732 270)
			(size 0.4318 0.4318)
			(layers "F.Cu" "F.Mask" "F.Paste")
			(net "M_G_CPU0_SB_DQ<12>")
		)
		(pad "DK28" smd circle
			(at -15.450058 14.746732 270)
			(size 0.4318 0.4318)
			(layers "F.Cu" "F.Mask" "F.Paste")
			(net "M_G_CPU0_SB_DQ<9>")
		)
		(pad "DK30" smd circle
			(at -13.822426 14.746732 270)
			(size 0.4318 0.4318)
			(layers "F.Cu" "F.Mask" "F.Paste")
			(net "GND")
		)
		(pad "DK32" smd circle
			(at -12.19454 14.746732 270)
			(size 0.4318 0.4318)
			(layers "F.Cu" "F.Mask" "F.Paste")
			(net "M_G_CPU0_SB_DQ<4>")
		)
		(pad "DK34" smd circle
			(at -10.566654 14.746732 270)
			(size 0.4318 0.4318)
			(layers "F.Cu" "F.Mask" "F.Paste")
			(net "M_G_CPU0_SB_DQ<1>")
		)
		(pad "DK36" smd circle
			(at -8.939022 14.746732 270)
			(size 0.4318 0.4318)
			(layers "F.Cu" "F.Mask" "F.Paste")
			(net "GND")
		)
		(pad "DK38" smd circle
			(at -7.311136 14.746732 270)
			(size 0.4318 0.4318)
			(layers "F.Cu" "F.Mask" "F.Paste")
			(net "M_H_CPU0_SB_CS_N<2>")
		)
		(pad "DK40" smd circle
			(at -5.68325 14.746732 270)
			(size 0.4318 0.4318)
			(layers "F.Cu" "F.Mask" "F.Paste")
			(net "M_H_CPU0_SB_CA<4>")
		)
		(pad "DK42" smd circle
			(at -4.055618 14.746732 270)
			(size 0.4318 0.4318)
			(layers "F.Cu" "F.Mask" "F.Paste")
			(net "GND")
		)
		(pad "DK44" smd circle
			(at -2.427732 14.746732 270)
			(size 0.4318 0.4318)
			(layers "F.Cu" "F.Mask" "F.Paste")
			(net "M_G_CPU0_SA_CA<6>")
		)
		(pad "DK47" smd circle
			(at 1.613916 14.856714 270)
			(size 0.4318 0.4318)
			(layers "F.Cu" "F.Mask" "F.Paste")
			(net "M_F_CPU0_SB_RSP<1>")
		)
		(pad "DK49" smd circle
			(at 3.241802 14.856714 270)
			(size 0.4318 0.4318)
			(layers "F.Cu" "F.Mask" "F.Paste")
			(net "GND")
		)
		(pad "DK51" smd circle
			(at 4.869434 14.856714 270)
			(size 0.4318 0.4318)
			(layers "F.Cu" "F.Mask" "F.Paste")
			(net "M_G_CPU0_SA_CA<2>")
		)
		(pad "DK53" smd circle
			(at 6.49732 14.856714 270)
			(size 0.4318 0.4318)
			(layers "F.Cu" "F.Mask" "F.Paste")
			(net "M_G_CPU0_SA_CS_N<3>")
		)
		(pad "DK55" smd circle
			(at 8.124952 14.856714 270)
			(size 0.4318 0.4318)
			(layers "F.Cu" "F.Mask" "F.Paste")
			(net "GND")
		)
		(pad "DK57" smd circle
			(at 9.752838 14.856714 270)
			(size 0.4318 0.4318)
			(layers "F.Cu" "F.Mask" "F.Paste")
			(net "M_G_CPU0_SA_CB<4>")
		)
		(pad "DK59" smd circle
			(at 11.380724 14.856714 270)
			(size 0.4318 0.4318)
			(layers "F.Cu" "F.Mask" "F.Paste")
			(net "M_G_CPU0_SA_CB<1>")
		)
		(pad "DK61" smd circle
			(at 13.008356 14.856714 270)
			(size 0.4318 0.4318)
			(layers "F.Cu" "F.Mask" "F.Paste")
			(net "GND")
		)
		(pad "DK63" smd circle
			(at 14.635988 14.856714 270)
			(size 0.4318 0.4318)
			(layers "F.Cu" "F.Mask" "F.Paste")
			(net "M_G_CPU0_SA_DQ<28>")
		)
		(pad "DK65" smd circle
			(at 16.263874 14.856714 270)
			(size 0.4318 0.4318)
			(layers "F.Cu" "F.Mask" "F.Paste")
			(net "M_G_CPU0_SA_DQ<25>")
		)
		(pad "DK67" smd circle
			(at 17.89176 14.856714 270)
			(size 0.4318 0.4318)
			(layers "F.Cu" "F.Mask" "F.Paste")
			(net "GND")
		)
		(pad "DK69" smd circle
			(at 19.519392 14.856714 270)
			(size 0.4318 0.4318)
			(layers "F.Cu" "F.Mask" "F.Paste")
			(net "M_G_CPU0_SA_DQ<12>")
		)
		(pad "DK71" smd circle
			(at 21.147278 14.856714 270)
			(size 0.4318 0.4318)
			(layers "F.Cu" "F.Mask" "F.Paste")
			(net "M_G_CPU0_SA_DQ<9>")
		)
		(pad "DK73" smd circle
			(at 22.77491 14.856714 270)
			(size 0.4318 0.4318)
			(layers "F.Cu" "F.Mask" "F.Paste")
			(net "GND")
		)
		(pad "DK75" smd circle
			(at 24.402796 14.856714 270)
			(size 0.4318 0.4318)
			(layers "F.Cu" "F.Mask" "F.Paste")
			(net "M_H_CPU0_SA_DQ<4>")
		)
		(pad "DK77" smd circle
			(at 26.030682 14.856714 270)
			(size 0.4318 0.4318)
			(layers "F.Cu" "F.Mask" "F.Paste")
			(net "GND")
		)
		(pad "DK79" smd circle
			(at 27.658314 14.856714 270)
			(size 0.4318 0.4318)
			(layers "F.Cu" "F.Mask" "F.Paste")
			(net "GND")
		)
		(pad "DK81" smd circle
			(at 29.2862 14.856714 270)
			(size 0.4318 0.4318)
			(layers "F.Cu" "F.Mask" "F.Paste")
			(net "GND")
		)
		(pad "DK83" smd circle
			(at 30.914086 14.856714 270)
			(size 0.4318 0.4318)
			(layers "F.Cu" "F.Mask" "F.Paste")
			(net "GND")
		)
		(pad "DK85" smd circle
			(at 32.541718 14.856714 270)
			(size 0.4318 0.4318)
			(layers "F.Cu" "F.Mask" "F.Paste")
			(net "P5E_CPU0_PE3_TX_DN<7>")
		)
		(pad "DK87" smd circle
			(at 34.169604 14.856714 270)
			(size 0.4318 0.4318)
			(layers "F.Cu" "F.Mask" "F.Paste")
			(net "GND")
		)
		(pad "DK89" smd circle
			(at 35.797236 14.856714 270)
			(size 0.4318 0.4318)
			(layers "F.Cu" "F.Mask" "F.Paste")
			(net "P5E_CPU0_PE3_RX_DP<8>")
		)
		(pad "DK91" smd oval
			(at 37.425122 14.856714)
			(size 0.381 0.4826)
			(drill
				(offset 0 -0.0508)
			)
			(layers "F.Cu" "F.Mask" "F.Paste")
			(net "GND")
		)
		(pad "DL1" smd oval
			(at -37.425122 15.216886 180)
			(size 0.381 0.4826)
			(drill
				(offset 0 -0.0508)
			)
			(layers "F.Cu" "F.Mask" "F.Paste")
			(net "GND")
		)
		(pad "DL3" smd circle
			(at -35.797236 15.216886 270)
			(size 0.4318 0.4318)
			(layers "F.Cu" "F.Mask" "F.Paste")
			(net "UPI_CPU1_CPU0_P0P1_DN<8>")
		)
		(pad "DL5" smd circle
			(at -34.169604 15.216886 270)
			(size 0.4318 0.4318)
			(layers "F.Cu" "F.Mask" "F.Paste")
			(net "GND")
		)
		(pad "DL7" smd circle
			(at -32.541718 15.216886 270)
			(size 0.4318 0.4318)
			(layers "F.Cu" "F.Mask" "F.Paste")
			(net "UPI_CPU0_CPU1_P1P0_DN<7>")
		)
		(pad "DL9" smd circle
			(at -30.914086 15.216886 270)
			(size 0.4318 0.4318)
			(layers "F.Cu" "F.Mask" "F.Paste")
			(net "GND")
		)
		(pad "DL11" smd circle
			(at -29.2862 15.216886 270)
			(size 0.4318 0.4318)
			(layers "F.Cu" "F.Mask" "F.Paste")
			(net "P5E_CPU0_PE2_RX_DP<7>")
		)
		(pad "DL13" smd circle
			(at -27.658314 15.216886 270)
			(size 0.4318 0.4318)
			(layers "F.Cu" "F.Mask" "F.Paste")
			(net "GND")
		)
		(pad "DL15" smd circle
			(at -26.030682 15.216886 270)
			(size 0.4318 0.4318)
			(layers "F.Cu" "F.Mask" "F.Paste")
			(net "P5E_CPU0_PE2_TX_DP<7>")
		)
		(pad "DL17" smd circle
			(at -24.402796 15.216886 270)
			(size 0.4318 0.4318)
			(layers "F.Cu" "F.Mask" "F.Paste")
			(net "GND")
		)
		(pad "DL19" smd circle
			(at -22.77491 15.216886 270)
			(size 0.4318 0.4318)
			(layers "F.Cu" "F.Mask" "F.Paste")
			(net "M_H_CPU0_SB_DQ<21>")
		)
		(pad "DL21" smd circle
			(at -21.147278 15.216886 270)
			(size 0.4318 0.4318)
			(layers "F.Cu" "F.Mask" "F.Paste")
			(net "M_H_CPU0_SB_DQS_DN<2>")
		)
		(pad "DL23" smd circle
			(at -19.519392 15.216886 270)
			(size 0.4318 0.4318)
			(layers "F.Cu" "F.Mask" "F.Paste")
			(net "M_H_CPU0_SB_DQ<16>")
		)
		(pad "DL25" smd circle
			(at -17.89176 15.216886 270)
			(size 0.4318 0.4318)
			(layers "F.Cu" "F.Mask" "F.Paste")
			(net "M_G_CPU0_SB_DQ<13>")
		)
		(pad "DL27" smd circle
			(at -16.263874 15.216886 270)
			(size 0.4318 0.4318)
			(layers "F.Cu" "F.Mask" "F.Paste")
			(net "M_G_CPU0_SB_DQS_DP<1>")
		)
		(pad "DL29" smd circle
			(at -14.635988 15.216886 270)
			(size 0.4318 0.4318)
			(layers "F.Cu" "F.Mask" "F.Paste")
			(net "M_G_CPU0_SB_DQ<10>")
		)
		(pad "DL31" smd circle
			(at -13.008356 15.216886 270)
			(size 0.4318 0.4318)
			(layers "F.Cu" "F.Mask" "F.Paste")
			(net "M_G_CPU0_SB_DQ<5>")
		)
		(pad "DL33" smd circle
			(at -11.380724 15.216886 270)
			(size 0.4318 0.4318)
			(layers "F.Cu" "F.Mask" "F.Paste")
			(net "M_G_CPU0_SB_DQS_DP<0>")
		)
		(pad "DL35" smd circle
			(at -9.752838 15.216886 270)
			(size 0.4318 0.4318)
			(layers "F.Cu" "F.Mask" "F.Paste")
			(net "M_G_CPU0_SB_DQ<0>")
		)
		(pad "DL37" smd circle
			(at -8.124952 15.216886 270)
			(size 0.4318 0.4318)
			(layers "F.Cu" "F.Mask" "F.Paste")
			(net "M_H_CPU0_SB_CS_N<0>")
		)
		(pad "DL39" smd circle
			(at -6.49732 15.216886 270)
			(size 0.4318 0.4318)
			(layers "F.Cu" "F.Mask" "F.Paste")
			(net "GND")
		)
		(pad "DL41" smd circle
			(at -4.869434 15.216886 270)
			(size 0.4318 0.4318)
			(layers "F.Cu" "F.Mask" "F.Paste")
			(net "M_H_CPU0_SB_CA<2>")
		)
		(pad "DL43" smd circle
			(at -3.241802 15.216886 270)
			(size 0.4318 0.4318)
			(layers "F.Cu" "F.Mask" "F.Paste")
			(net "M_G_CPU0_SA_PAR")
		)
		(pad "DL45" smd circle
			(at -1.613916 15.216886 270)
			(size 0.4318 0.4318)
			(layers "F.Cu" "F.Mask" "F.Paste")
			(net "M_G_CPU0_CLK_DN<1>")
		)
		(pad "DL48" smd circle
			(at 2.427732 15.326868 270)
			(size 0.4318 0.4318)
			(layers "F.Cu" "F.Mask" "F.Paste")
			(net "M_F_CPU0_SB_RSP<0>")
		)
		(pad "DL50" smd circle
			(at 4.055618 15.326868 270)
			(size 0.4318 0.4318)
			(layers "F.Cu" "F.Mask" "F.Paste")
			(net "M_G_CPU0_SA_CA<4>")
		)
		(pad "DL52" smd circle
			(at 5.68325 15.326868 270)
			(size 0.4318 0.4318)
			(layers "F.Cu" "F.Mask" "F.Paste")
			(net "GND")
		)
		(pad "DL54" smd circle
			(at 7.311136 15.326868 270)
			(size 0.4318 0.4318)
			(layers "F.Cu" "F.Mask" "F.Paste")
			(net "M_G_CPU0_SA_CS_N<2>")
		)
		(pad "DL56" smd circle
			(at 8.939022 15.326868 270)
			(size 0.4318 0.4318)
			(layers "F.Cu" "F.Mask" "F.Paste")
			(net "M_G_CPU0_SA_CB<5>")
		)
		(pad "DL58" smd circle
			(at 10.566654 15.326868 270)
			(size 0.4318 0.4318)
			(layers "F.Cu" "F.Mask" "F.Paste")
			(net "M_G_CPU0_SA_DQS_DN<4>")
		)
		(pad "DL60" smd circle
			(at 12.19454 15.326868 270)
			(size 0.4318 0.4318)
			(layers "F.Cu" "F.Mask" "F.Paste")
			(net "M_G_CPU0_SA_CB<0>")
		)
		(pad "DL62" smd circle
			(at 13.822426 15.326868 270)
			(size 0.4318 0.4318)
			(layers "F.Cu" "F.Mask" "F.Paste")
			(net "M_G_CPU0_SA_DQ<29>")
		)
		(pad "DL64" smd circle
			(at 15.450058 15.326868 270)
			(size 0.4318 0.4318)
			(layers "F.Cu" "F.Mask" "F.Paste")
			(net "M_G_CPU0_SA_DQS_DN<3>")
		)
		(pad "DL66" smd circle
			(at 17.07769 15.326868 270)
			(size 0.4318 0.4318)
			(layers "F.Cu" "F.Mask" "F.Paste")
			(net "M_G_CPU0_SA_DQ<24>")
		)
		(pad "DL68" smd circle
			(at 18.705576 15.326868 270)
			(size 0.4318 0.4318)
			(layers "F.Cu" "F.Mask" "F.Paste")
			(net "M_G_CPU0_SA_DQ<13>")
		)
		(pad "DL70" smd circle
			(at 20.333462 15.326868 270)
			(size 0.4318 0.4318)
			(layers "F.Cu" "F.Mask" "F.Paste")
			(net "M_G_CPU0_SA_DQS_DP<1>")
		)
		(pad "DL72" smd circle
			(at 21.961094 15.326868 270)
			(size 0.4318 0.4318)
			(layers "F.Cu" "F.Mask" "F.Paste")
			(net "M_G_CPU0_SA_DQ<8>")
		)
		(pad "DL74" smd circle
			(at 23.58898 15.326868 270)
			(size 0.4318 0.4318)
			(layers "F.Cu" "F.Mask" "F.Paste")
			(net "M_H_CPU0_SA_DQ<5>")
		)
		(pad "DL76" smd circle
			(at 25.216612 15.326868 270)
			(size 0.4318 0.4318)
			(layers "F.Cu" "F.Mask" "F.Paste")
			(net "M_H_CPU0_SA_DQS_DP<0>")
		)
		(pad "DL78" smd circle
			(at 26.844498 15.326868 270)
			(size 0.4318 0.4318)
			(layers "F.Cu" "F.Mask" "F.Paste")
			(net "GND")
		)
		(pad "DL80" smd circle
			(at 28.472384 15.326868 270)
			(size 0.4318 0.4318)
			(layers "F.Cu" "F.Mask" "F.Paste")
			(net "Net_698")
		)
		(pad "DL82" smd circle
			(at 30.100016 15.326868 270)
			(size 0.4318 0.4318)
			(layers "F.Cu" "F.Mask" "F.Paste")
			(net "Net_675")
		)
		(pad "DL84" smd circle
			(at 31.727902 15.326868 270)
			(size 0.4318 0.4318)
			(layers "F.Cu" "F.Mask" "F.Paste")
			(net "GND")
		)
		(pad "DL86" smd circle
			(at 33.355534 15.326868 270)
			(size 0.4318 0.4318)
			(layers "F.Cu" "F.Mask" "F.Paste")
			(net "P5E_CPU0_PE3_TX_DP<7>")
		)
		(pad "DL88" smd circle
			(at 34.98342 15.326868 270)
			(size 0.4318 0.4318)
			(layers "F.Cu" "F.Mask" "F.Paste")
			(net "GND")
		)
		(pad "DL90" smd circle
			(at 36.611306 15.326868 270)
			(size 0.4318 0.4318)
			(layers "F.Cu" "F.Mask" "F.Paste")
			(net "P5E_CPU0_PE3_RX_DN<8>")
		)
		(pad "DM2" smd circle
			(at -36.611306 15.686532 270)
			(size 0.4318 0.4318)
			(layers "F.Cu" "F.Mask" "F.Paste")
			(net "UPI_CPU1_CPU0_P0P1_DP<8>")
		)
		(pad "DM4" smd circle
			(at -34.98342 15.686532 270)
			(size 0.4318 0.4318)
			(layers "F.Cu" "F.Mask" "F.Paste")
			(net "GND")
		)
		(pad "DM6" smd circle
			(at -33.355534 15.686532 270)
			(size 0.4318 0.4318)
			(layers "F.Cu" "F.Mask" "F.Paste")
			(net "UPI_CPU0_CPU1_P1P0_DP<7>")
		)
		(pad "DM8" smd circle
			(at -31.727902 15.686532 270)
			(size 0.4318 0.4318)
			(layers "F.Cu" "F.Mask" "F.Paste")
			(net "GND")
		)
		(pad "DM10" smd circle
			(at -30.100016 15.686532 270)
			(size 0.4318 0.4318)
			(layers "F.Cu" "F.Mask" "F.Paste")
			(net "P5E_CPU0_PE2_RX_DN<7>")
		)
		(pad "DM12" smd circle
			(at -28.472384 15.686532 270)
			(size 0.4318 0.4318)
			(layers "F.Cu" "F.Mask" "F.Paste")
			(net "GND")
		)
		(pad "DM14" smd circle
			(at -26.844498 15.686532 270)
			(size 0.4318 0.4318)
			(layers "F.Cu" "F.Mask" "F.Paste")
			(net "P5E_CPU0_PE2_TX_DP<8>")
		)
		(pad "DM16" smd circle
			(at -25.216612 15.686532 270)
			(size 0.4318 0.4318)
			(layers "F.Cu" "F.Mask" "F.Paste")
			(net "GND")
		)
		(pad "DM18" smd circle
			(at -23.58898 15.686532 270)
			(size 0.4318 0.4318)
			(layers "F.Cu" "F.Mask" "F.Paste")
			(net "GND")
		)
		(pad "DM20" smd circle
			(at -21.961094 15.686532 270)
			(size 0.4318 0.4318)
			(layers "F.Cu" "F.Mask" "F.Paste")
			(net "GND")
		)
		(pad "DM22" smd circle
			(at -20.333462 15.686532 270)
			(size 0.4318 0.4318)
			(layers "F.Cu" "F.Mask" "F.Paste")
			(net "GND")
		)
		(pad "DM24" smd circle
			(at -18.705576 15.686532 270)
			(size 0.4318 0.4318)
			(layers "F.Cu" "F.Mask" "F.Paste")
			(net "GND")
		)
		(pad "DM26" smd circle
			(at -17.07769 15.686532 270)
			(size 0.4318 0.4318)
			(layers "F.Cu" "F.Mask" "F.Paste")
			(net "GND")
		)
		(pad "DM28" smd circle
			(at -15.450058 15.686532 270)
			(size 0.4318 0.4318)
			(layers "F.Cu" "F.Mask" "F.Paste")
			(net "GND")
		)
		(pad "DM30" smd circle
			(at -13.822426 15.686532 270)
			(size 0.4318 0.4318)
			(layers "F.Cu" "F.Mask" "F.Paste")
			(net "GND")
		)
		(pad "DM32" smd circle
			(at -12.19454 15.686532 270)
			(size 0.4318 0.4318)
			(layers "F.Cu" "F.Mask" "F.Paste")
			(net "GND")
		)
		(pad "DM34" smd circle
			(at -10.566654 15.686532 270)
			(size 0.4318 0.4318)
			(layers "F.Cu" "F.Mask" "F.Paste")
			(net "GND")
		)
		(pad "DM36" smd circle
			(at -8.939022 15.686532 270)
			(size 0.4318 0.4318)
			(layers "F.Cu" "F.Mask" "F.Paste")
			(net "GND")
		)
		(pad "DM38" smd circle
			(at -7.311136 15.686532 270)
			(size 0.4318 0.4318)
			(layers "F.Cu" "F.Mask" "F.Paste")
			(net "GND")
		)
		(pad "DM40" smd circle
			(at -5.68325 15.686532 270)
			(size 0.4318 0.4318)
			(layers "F.Cu" "F.Mask" "F.Paste")
			(net "GND")
		)
		(pad "DM42" smd circle
			(at -4.055618 15.686532 270)
			(size 0.4318 0.4318)
			(layers "F.Cu" "F.Mask" "F.Paste")
			(net "GND")
		)
		(pad "DM44" smd circle
			(at -2.427732 15.686532 270)
			(size 0.4318 0.4318)
			(layers "F.Cu" "F.Mask" "F.Paste")
			(net "GND")
		)
		(pad "DM47" smd circle
			(at 1.613916 15.796514 270)
			(size 0.4318 0.4318)
			(layers "F.Cu" "F.Mask" "F.Paste")
			(net "GND")
		)
		(pad "DM49" smd circle
			(at 3.241802 15.796514 270)
			(size 0.4318 0.4318)
			(layers "F.Cu" "F.Mask" "F.Paste")
			(net "GND")
		)
		(pad "DM51" smd circle
			(at 4.869434 15.796514 270)
			(size 0.4318 0.4318)
			(layers "F.Cu" "F.Mask" "F.Paste")
			(net "GND")
		)
		(pad "DM53" smd circle
			(at 6.49732 15.796514 270)
			(size 0.4318 0.4318)
			(layers "F.Cu" "F.Mask" "F.Paste")
			(net "GND")
		)
		(pad "DM55" smd circle
			(at 8.124952 15.796514 270)
			(size 0.4318 0.4318)
			(layers "F.Cu" "F.Mask" "F.Paste")
			(net "GND")
		)
		(pad "DM57" smd circle
			(at 9.752838 15.796514 270)
			(size 0.4318 0.4318)
			(layers "F.Cu" "F.Mask" "F.Paste")
			(net "GND")
		)
		(pad "DM59" smd circle
			(at 11.380724 15.796514 270)
			(size 0.4318 0.4318)
			(layers "F.Cu" "F.Mask" "F.Paste")
			(net "GND")
		)
		(pad "DM61" smd circle
			(at 13.008356 15.796514 270)
			(size 0.4318 0.4318)
			(layers "F.Cu" "F.Mask" "F.Paste")
			(net "GND")
		)
		(pad "DM63" smd circle
			(at 14.635988 15.796514 270)
			(size 0.4318 0.4318)
			(layers "F.Cu" "F.Mask" "F.Paste")
			(net "GND")
		)
	)
)
